(kicad_pcb
	(version 20260206)
	(generator "pcbnew")
	(generator_version "10.0")
	(general
		(thickness 1.6)
		(legacy_teardrops no)
	)
	(paper "A4")
	(title_block
		(title "Bryce Canyon_F.DPB_16315-1-OCP.brd")
		(comment 1 "Bryce Canyon / footprints 1160-1164 of 2223")
	)
	(layers
		(0 "F.Cu" signal "TOP")
		(4 "In1.Cu" signal "L2GND")
		(6 "In2.Cu" signal "L3")
		(8 "In3.Cu" signal "L4GND")
		(10 "In4.Cu" signal "L5")
		(12 "In5.Cu" signal "L6VCC")
		(14 "In6.Cu" signal "L7VCC")
		(16 "In7.Cu" signal "L8")
		(18 "In8.Cu" signal "L9GND")
		(20 "In9.Cu" signal "L10")
		(22 "In10.Cu" signal "L11GND")
		(2 "B.Cu" signal "BOTTOM")
		(9 "F.Adhes" user "F.Adhesive")
		(11 "B.Adhes" user "B.Adhesive")
		(13 "F.Paste" user "Package Geometry/Pastemask Top")
		(15 "B.Paste" user "Package Geometry/Pastemask Bottom")
		(5 "F.SilkS" user "Ref Des/Silkscreen Top")
		(7 "B.SilkS" user "Ref Des/Silkscreen Bottom")
		(1 "F.Mask" user "Board Geometry/Soldermask Top")
		(3 "B.Mask" user "Board Geometry/Soldermask Bottom")
		(17 "Dwgs.User" user "User.Drawings")
		(19 "Cmts.User" user "User.Comments")
		(21 "Eco1.User" user "User.Eco1")
		(23 "Eco2.User" user "User.Eco2")
		(25 "Edge.Cuts" user "Board Geometry/Outline")
		(27 "Margin" user)
		(31 "F.CrtYd" user "Package Geometry/Place Bound Top")
		(29 "B.CrtYd" user "Package Geometry/Place Bound Bottom")
		(35 "F.Fab" user "Ref Des/Assembly Top")
		(33 "B.Fab" user "Ref Des/Assembly Bottom")
	)
	(footprint ""
		(layer "F.Cu")
		(at 334.68437 -29.095954)
		(property "Reference" "C16"
			(at 0 0 0)
			(layer "F.SilkS")
			(hide yes)
			(effects
				(font
					(size 1.27 1.27)
				)
			)
		)
		(property "Value" "SCD1U16V2KX-3GP"
			(at 1.1811 -2.7051 0)
			(unlocked yes)
			(layer "F.Fab")
			(hide yes)
			(effects
				(font
					(size 1.016 1.016)
					(thickness 0.1524)
				)
			)
		)
		(property "Device Type" "C402H22"
			(at 1.1811 -4.2291 0)
			(unlocked yes)
			(layer "F.Fab")
			(hide yes)
			(effects
				(font
					(size 1.016 1.016)
					(thickness 0.1524)
				)
			)
		)
		(duplicate_pad_numbers_are_jumpers no)
		(fp_rect
			(start -0.4318 0.9525)
			(end 0.4318 -0.9525)
			(stroke
				(width 0)
				(type default)
			)
			(fill no)
			(layer "F.CrtYd")
		)
		(fp_rect
			(start -0.4318 0.9525)
			(end 0.4318 -0.9525)
			(stroke
				(width 0)
				(type default)
			)
			(fill no)
			(layer "F.Fab")
		)
		(pad "1" smd custom
			(at 0 -0.4445)
			(size 0.1524 0.1524)
			(layers "F.Cu" "F.Mask" "F.Paste")
			(net "P3V3_STBY_B")
			(options
				(clearance outline)
				(anchor circle)
			)
			(primitives
				(gr_poly
					(pts
						(arc
							(start 0.3048 -0.2032)
							(mid 0.275042 -0.275042)
							(end 0.2032 -0.3048)
						)
						(arc
							(start -0.2032 -0.3048)
							(mid -0.275042 -0.275042)
							(end -0.3048 -0.2032)
						)
						(arc
							(start -0.3048 0.2032)
							(mid -0.275042 0.275042)
							(end -0.2032 0.3048)
						)
						(arc
							(start 0.2032 0.3048)
							(mid 0.275042 0.275042)
							(end 0.3048 0.2032)
						)
					)
					(width 0)
					(fill yes)
				)
			)
		)
		(pad "2" smd custom
			(at 0 0.4445)
			(size 0.1524 0.1524)
			(layers "F.Cu" "F.Mask" "F.Paste")
			(net "GND")
			(options
				(clearance outline)
				(anchor circle)
			)
			(primitives
				(gr_poly
					(pts
						(arc
							(start 0.3048 -0.2032)
							(mid 0.275042 -0.275042)
							(end 0.2032 -0.3048)
						)
						(arc
							(start -0.2032 -0.3048)
							(mid -0.275042 -0.275042)
							(end -0.3048 -0.2032)
						)
						(arc
							(start -0.3048 0.2032)
							(mid -0.275042 0.275042)
							(end -0.2032 0.3048)
						)
						(arc
							(start 0.2032 0.3048)
							(mid 0.275042 0.275042)
							(end 0.3048 0.2032)
						)
					)
					(width 0)
					(fill yes)
				)
			)
		)
	)
	(footprint ""
		(layer "F.Cu")
		(at 349.812102 -177.169318 90)
		(property "Reference" "R567"
			(at 0 0 90)
			(layer "F.SilkS")
			(hide yes)
			(effects
				(font
					(size 1.27 1.27)
				)
			)
		)
		(property "Value" "10KR2F-2-GP"
			(at 0.064008 -3.993896 90)
			(unlocked yes)
			(layer "F.Fab")
			(hide yes)
			(effects
				(font
					(size 1.016 1.016)
					(thickness 0.1524)
				)
			)
		)
		(property "Device Type" "R402H16"
			(at 0.064008 -5.517896 90)
			(unlocked yes)
			(layer "F.Fab")
			(hide yes)
			(effects
				(font
					(size 1.016 1.016)
					(thickness 0.1524)
				)
			)
		)
		(duplicate_pad_numbers_are_jumpers no)
		(fp_line
			(start 0.508 -0.9398)
			(end -0.508 -0.9398)
			(stroke
				(width 0.1524)
				(type default)
			)
			(layer "F.SilkS")
		)
		(fp_line
			(start -0.508 -0.9398)
			(end -0.508 0.9398)
			(stroke
				(width 0.1524)
				(type default)
			)
			(layer "F.SilkS")
		)
		(fp_rect
			(start -0.508 0.9398)
			(end 0.508 -0.9398)
			(stroke
				(width 0)
				(type default)
			)
			(fill no)
			(layer "F.CrtYd")
		)
		(fp_rect
			(start -0.508 0.9398)
			(end 0.508 -0.9398)
			(stroke
				(width 0)
				(type default)
			)
			(fill no)
			(layer "F.Fab")
		)
		(pad "1" smd custom
			(at 0 -0.4445 90)
			(size 0.1397 0.1397)
			(layers "F.Cu" "F.Mask" "F.Paste")
			(net "P3V3_STBY_A")
			(options
				(clearance outline)
				(anchor circle)
			)
			(primitives
				(gr_poly
					(pts
						(arc
							(start -0.1778 -0.2794)
							(mid -0.249642 -0.249642)
							(end -0.2794 -0.1778)
						)
						(arc
							(start -0.2794 0.1778)
							(mid -0.249642 0.249642)
							(end -0.1778 0.2794)
						)
						(arc
							(start 0.1778 0.2794)
							(mid 0.249642 0.249642)
							(end 0.2794 0.1778)
						)
						(arc
							(start 0.2794 -0.1778)
							(mid 0.249642 -0.249642)
							(end 0.1778 -0.2794)
						)
					)
					(width 0)
					(fill yes)
				)
			)
		)
		(pad "2" smd custom
			(at 0 0.4445 90)
			(size 0.1397 0.1397)
			(layers "F.Cu" "F.Mask" "F.Paste")
			(net "HDD_PRSNT_19")
			(options
				(clearance outline)
				(anchor circle)
			)
			(primitives
				(gr_poly
					(pts
						(arc
							(start -0.1778 -0.2794)
							(mid -0.249642 -0.249642)
							(end -0.2794 -0.1778)
						)
						(arc
							(start -0.2794 0.1778)
							(mid -0.249642 0.249642)
							(end -0.1778 0.2794)
						)
						(arc
							(start 0.1778 0.2794)
							(mid 0.249642 0.249642)
							(end 0.2794 0.1778)
						)
						(arc
							(start 0.2794 -0.1778)
							(mid 0.249642 -0.249642)
							(end 0.1778 -0.2794)
						)
					)
					(width 0)
					(fill yes)
				)
			)
		)
	)
	(footprint ""
		(layer "F.Cu")
		(at 255.498092 -18.418556 -90)
		(property "Reference" "TP245"
			(at 0 0 270)
			(layer "F.SilkS")
			(hide yes)
			(effects
				(font
					(size 1.27 1.27)
				)
			)
		)
		(property "Value" "TPAD32-GP"
			(at -0.0508 -1.6764 270)
			(unlocked yes)
			(layer "F.Fab")
			(hide yes)
			(effects
				(font
					(size 1.016 1.016)
					(thickness 0.1524)
				)
			)
		)
		(property "Device Type" "TPAD32"
			(at -0.0508 -3.2004 270)
			(unlocked yes)
			(layer "F.Fab")
			(hide yes)
			(effects
				(font
					(size 1.016 1.016)
					(thickness 0.1524)
				)
			)
		)
		(duplicate_pad_numbers_are_jumpers no)
		(fp_poly
			(pts
				(arc
					(start 0 -0.4064)
					(mid 0 0.4064)
					(end 0 -0.4064)
				)
			)
			(stroke
				(width 0)
				(type default)
			)
			(fill no)
			(layer "F.CrtYd")
		)
		(fp_poly
			(pts
				(arc
					(start 0 -0.7112)
					(mid 0 0.7112)
					(end 0 -0.7112)
				)
			)
			(stroke
				(width 0)
				(type default)
			)
			(fill no)
			(layer "F.Fab")
		)
		(pad "1" smd circle
			(at 0 0 270)
			(size 0.8128 0.8128)
			(layers "F.Cu" "F.Mask" "F.Paste")
			(net "TP_PCIE_COMP_A_CLK_P5")
		)
	)
	(footprint ""
		(layer "F.Cu")
		(at 406.711912 -242.831112 180)
		(property "Reference" "Q236"
			(at 0 0 180)
			(layer "F.SilkS")
			(hide yes)
			(effects
				(font
					(size 1.27 1.27)
				)
			)
		)
		(property "Value" "2N7002K-2-GP"
			(at 0.127 -8.9662 180)
			(unlocked yes)
			(layer "F.Fab")
			(hide yes)
			(effects
				(font
					(size 1.016 1.016)
					(thickness 0.1524)
				)
			)
		)
		(property "Device Type" "SOT23DGS2D4H44"
			(at 0.127 -10.4902 180)
			(unlocked yes)
			(layer "F.Fab")
			(hide yes)
			(effects
				(font
					(size 1.016 1.016)
					(thickness 0.1524)
				)
			)
		)
		(duplicate_pad_numbers_are_jumpers no)
		(fp_line
			(start 1.651 1.778)
			(end 1.651 -1.778)
			(stroke
				(width 0.1524)
				(type default)
			)
			(layer "F.SilkS")
		)
		(fp_line
			(start 1.651 -1.778)
			(end -1.651 -1.778)
			(stroke
				(width 0.1524)
				(type default)
			)
			(layer "F.SilkS")
		)
		(fp_line
			(start -1.651 1.778)
			(end 1.651 1.778)
			(stroke
				(width 0.1524)
				(type default)
			)
			(layer "F.SilkS")
		)
		(fp_line
			(start -1.651 -1.778)
			(end -1.651 1.778)
			(stroke
				(width 0.1524)
				(type default)
			)
			(layer "F.SilkS")
		)
		(fp_poly
			(pts
				(xy -1.778 1.8796) (xy -1.778 -1.8796) (xy 1.778 -1.8796) (xy 1.778 1.8796)
			)
			(stroke
				(width 0)
				(type default)
			)
			(fill no)
			(layer "F.CrtYd")
		)
		(fp_poly
			(pts
				(xy -1.778 1.8796) (xy -1.778 -1.8796) (xy 1.778 -1.8796) (xy 1.778 1.8796)
			)
			(stroke
				(width 0)
				(type default)
			)
			(fill no)
			(layer "F.Fab")
		)
		(pad "D" smd custom
			(at 0 -0.9525 180)
			(size 0.1905 0.1905)
			(layers "F.Cu" "F.Mask" "F.Paste")
			(net "FLT_HDD9_N")
			(options
				(clearance outline)
				(anchor circle)
			)
			(primitives
				(gr_poly
					(pts
						(arc
							(start -0.1778 0.5715)
							(mid -0.321484 0.511984)
							(end -0.381 0.3683)
						)
						(arc
							(start -0.381 -0.3683)
							(mid -0.321484 -0.511984)
							(end -0.1778 -0.5715)
						)
						(arc
							(start 0.1778 -0.5715)
							(mid 0.321484 -0.511984)
							(end 0.381 -0.3683)
						)
						(arc
							(start 0.381 0.3683)
							(mid 0.321484 0.511984)
							(end 0.1778 0.5715)
						)
					)
					(width 0)
					(fill yes)
				)
			)
		)
		(pad "G" smd custom
			(at -0.98425 0.9525 180)
			(size 0.1905 0.1905)
			(layers "F.Cu" "F.Mask" "F.Paste")
			(net "DRIVE_A_9_FLT_LED")
			(options
				(clearance outline)
				(anchor circle)
			)
			(primitives
				(gr_poly
					(pts
						(arc
							(start -0.1778 0.5715)
							(mid -0.321484 0.511984)
							(end -0.381 0.3683)
						)
						(arc
							(start -0.381 -0.3683)
							(mid -0.321484 -0.511984)
							(end -0.1778 -0.5715)
						)
						(arc
							(start 0.1778 -0.5715)
							(mid 0.321484 -0.511984)
							(end 0.381 -0.3683)
						)
						(arc
							(start 0.381 0.3683)
							(mid 0.321484 0.511984)
							(end 0.1778 0.5715)
						)
					)
					(width 0)
					(fill yes)
				)
			)
		)
		(pad "S" smd custom
			(at 0.98425 0.9525 180)
			(size 0.1905 0.1905)
			(layers "F.Cu" "F.Mask" "F.Paste")
			(net "GND")
			(options
				(clearance outline)
				(anchor circle)
			)
			(primitives
				(gr_poly
					(pts
						(arc
							(start -0.1778 0.5715)
							(mid -0.321484 0.511984)
							(end -0.381 0.3683)
						)
						(arc
							(start -0.381 -0.3683)
							(mid -0.321484 -0.511984)
							(end -0.1778 -0.5715)
						)
						(arc
							(start 0.1778 -0.5715)
							(mid 0.321484 -0.511984)
							(end 0.381 -0.3683)
						)
						(arc
							(start 0.381 0.3683)
							(mid 0.321484 0.511984)
							(end 0.1778 0.5715)
						)
					)
					(width 0)
					(fill yes)
				)
			)
		)
	)
	(footprint ""
		(layer "F.Cu")
		(at 56.314848 -242.20297)
		(property "Reference" "R199"
			(at 0 0 0)
			(layer "F.SilkS")
			(hide yes)
			(effects
				(font
					(size 1.27 1.27)
				)
			)
		)
		(property "Value" "91R3F-1-GP"
			(at -0.0254 -2.5146 0)
			(unlocked yes)
			(layer "F.Fab")
			(hide yes)
			(effects
				(font
					(size 1.016 1.016)
					(thickness 0.1524)
				)
			)
		)
		(property "Device Type" "R603H22"
			(at -0.0254 -4.0386 0)
			(unlocked yes)
			(layer "F.Fab")
			(hide yes)
			(effects
				(font
					(size 1.016 1.016)
					(thickness 0.1524)
				)
			)
		)
		(duplicate_pad_numbers_are_jumpers no)
		(fp_line
			(start -0.4826 0)
			(end -0.2032 0)
			(stroke
				(width 0.2032)
				(type default)
			)
			(layer "F.SilkS")
		)
		(fp_line
			(start 0.2032 0)
			(end 0.4826 0)
			(stroke
				(width 0.2032)
				(type default)
			)
			(layer "F.SilkS")
		)
		(fp_rect
			(start -0.5842 1.3335)
			(end 0.5842 -1.3335)
			(stroke
				(width 0)
				(type default)
			)
			(fill no)
			(layer "F.CrtYd")
		)
		(fp_rect
			(start -0.5842 1.3335)
			(end 0.5842 -1.3335)
			(stroke
				(width 0)
				(type default)
			)
			(fill no)
			(layer "F.Fab")
		)
		(pad "1" smd custom
			(at 0 -0.762)
			(size 0.2159 0.2159)
			(layers "F.Cu" "F.Mask" "F.Paste")
			(net "P5V_A_1")
			(options
				(clearance outline)
				(anchor circle)
			)
			(primitives
				(gr_poly
					(pts
						(arc
							(start -0.3302 -0.4318)
							(mid -0.402042 -0.402042)
							(end -0.4318 -0.3302)
						)
						(arc
							(start -0.4318 0.3302)
							(mid -0.402042 0.402042)
							(end -0.3302 0.4318)
						)
						(arc
							(start 0.3302 0.4318)
							(mid 0.402042 0.402042)
							(end 0.4318 0.3302)
						)
						(arc
							(start 0.4318 -0.3302)
							(mid 0.402042 -0.402042)
							(end 0.3302 -0.4318)
						)
					)
					(width 0)
					(fill yes)
				)
			)
		)
		(pad "2" smd custom
			(at 0 0.762)
			(size 0.2159 0.2159)
			(layers "F.Cu" "F.Mask" "F.Paste")
			(net "DRV_ACT_1")
			(options
				(clearance outline)
				(anchor circle)
			)
			(primitives
				(gr_poly
					(pts
						(arc
							(start -0.3302 -0.4318)
							(mid -0.402042 -0.402042)
							(end -0.4318 -0.3302)
						)
						(arc
							(start -0.4318 0.3302)
							(mid -0.402042 0.402042)
							(end -0.3302 0.4318)
						)
						(arc
							(start 0.3302 0.4318)
							(mid 0.402042 0.402042)
							(end 0.4318 0.3302)
						)
						(arc
							(start 0.4318 -0.3302)
							(mid 0.402042 -0.402042)
							(end 0.3302 -0.4318)
						)
					)
					(width 0)
					(fill yes)
				)
			)
		)
	)
)
